(kicad_pcb
	(version 20260206)
	(generator "pcbnew")
	(generator_version "10.0")
	(general
		(thickness 1.6)
		(legacy_teardrops no)
	)
	(paper "A4")
	(title_block
		(title "v1-pdb — T6M_PDB_D_0927_0900.brd")
		(comment 1 "Open CloudServer (Microsoft) / footprints 149-150 of 321")
	)
	(layers
		(0 "F.Cu" signal "TOP")
		(4 "In1.Cu" signal "GND")
		(6 "In2.Cu" signal "IN1")
		(8 "In3.Cu" signal "VCC")
		(10 "In4.Cu" signal "VCC1")
		(12 "In5.Cu" signal "IN2")
		(14 "In6.Cu" signal "GND1")
		(2 "B.Cu" signal "BOTTOM")
		(9 "F.Adhes" user "F.Adhesive")
		(11 "B.Adhes" user "B.Adhesive")
		(13 "F.Paste" user "Package Geometry/Pastemask Top")
		(15 "B.Paste" user "Package Geometry/Pastemask Bottom")
		(5 "F.SilkS" user "Ref Des/Silkscreen Top")
		(7 "B.SilkS" user "Ref Des/Silkscreen Bottom")
		(1 "F.Mask" user "Board Geometry/Soldermask Top")
		(3 "B.Mask" user "Board Geometry/Soldermask Bottom")
		(17 "Dwgs.User" user "User.Drawings")
		(19 "Cmts.User" user "User.Comments")
		(21 "Eco1.User" user "User.Eco1")
		(23 "Eco2.User" user "User.Eco2")
		(25 "Edge.Cuts" user "Board Geometry/Outline")
		(27 "Margin" user)
		(31 "F.CrtYd" user "Package Geometry/Place Bound Top")
		(29 "B.CrtYd" user "Package Geometry/Place Bound Bottom")
		(35 "F.Fab" user "Ref Des/Assembly Top")
		(33 "B.Fab" user "Ref Des/Assembly Bottom")
	)
	(footprint ""
		(layer "F.Cu")
		(at 16.599916 -295.89984)
		(property "Reference" "H4"
			(at -1.466596 -9.400032 0)
			(unlocked yes)
			(layer "F.SilkS")
			(effects
				(font
					(size 0.7874 0.5842)
					(thickness 0.1524)
				)
				(justify left)
			)
		)
		(property "Value" ""
			(at 0 0 0)
			(layer "F.Fab")
			(effects
				(font
					(size 1.27 1.27)
				)
			)
		)
		(duplicate_pad_numbers_are_jumpers no)
		(fp_circle
			(center 0 0)
			(end 7.999984 0)
			(stroke
				(width 0.1524)
				(type default)
			)
			(fill no)
			(layer "F.SilkS")
		)
		(fp_circle
			(center 0 0)
			(end 14.7066 0)
			(stroke
				(width 0.1524)
				(type default)
			)
			(fill no)
			(layer "B.SilkS")
		)
		(fp_poly
			(pts
				(arc
					(start 0 5.0038)
					(mid 0 -5.0038)
					(end 0 5.0038)
				)
			)
			(stroke
				(width 0)
				(type default)
			)
			(fill no)
			(layer "F.CrtYd")
		)
		(pad "" np_thru_hole circle
			(at 0 0)
			(size 4.0132 4.0132)
			(drill 4.0132)
			(layers "*.Cu" "*.Mask")
			(clearance 0.381)
			(thermal_gap 0.381)
		)
		(pad "2" thru_hole circle
			(at 0 -3.50012)
			(size 0.762 0.762)
			(drill 0.5588)
			(layers "*.Cu" "*.Mask")
			(remove_unused_layers no)
			(net "GND")
			(clearance 0.1524)
			(thermal_gap 0.1524)
		)
		(pad "3" thru_hole circle
			(at -2.500122 -2.500122)
			(size 0.762 0.762)
			(drill 0.5588)
			(layers "*.Cu" "*.Mask")
			(remove_unused_layers no)
			(net "GND")
			(clearance 0.1524)
			(thermal_gap 0.1524)
		)
		(pad "4" thru_hole circle
			(at -3.50012 0)
			(size 0.762 0.762)
			(drill 0.5588)
			(layers "*.Cu" "*.Mask")
			(remove_unused_layers no)
			(net "GND")
			(clearance 0.1524)
			(thermal_gap 0.1524)
		)
		(pad "5" thru_hole circle
			(at -2.500122 2.500122)
			(size 0.762 0.762)
			(drill 0.5588)
			(layers "*.Cu" "*.Mask")
			(remove_unused_layers no)
			(net "GND")
			(clearance 0.1524)
			(thermal_gap 0.1524)
		)
		(pad "6" thru_hole circle
			(at 0 3.50012)
			(size 0.762 0.762)
			(drill 0.5588)
			(layers "*.Cu" "*.Mask")
			(remove_unused_layers no)
			(net "GND")
			(clearance 0.1524)
			(thermal_gap 0.1524)
		)
		(pad "7" thru_hole circle
			(at 2.500122 2.500122)
			(size 0.762 0.762)
			(drill 0.5588)
			(layers "*.Cu" "*.Mask")
			(remove_unused_layers no)
			(net "GND")
			(clearance 0.1524)
			(thermal_gap 0.1524)
		)
		(pad "8" thru_hole circle
			(at 3.50012 0)
			(size 0.762 0.762)
			(drill 0.5588)
			(layers "*.Cu" "*.Mask")
			(remove_unused_layers no)
			(net "GND")
			(clearance 0.1524)
			(thermal_gap 0.1524)
		)
		(pad "9" thru_hole circle
			(at 2.500122 -2.500122)
			(size 0.762 0.762)
			(drill 0.5588)
			(layers "*.Cu" "*.Mask")
			(remove_unused_layers no)
			(net "GND")
			(clearance 0.1524)
			(thermal_gap 0.1524)
		)
		(zone
			(layer "F.Cu")
			(hatch none 0.5)
			(connect_pads
				(clearance 0)
			)
			(min_thickness 0.25)
			(keepout
				(tracks not_allowed)
				(vias allowed)
				(pads allowed)
				(copperpour not_allowed)
				(footprints allowed)
			)
			(placement
				(enabled no)
				(sheetname "")
			)
			(fill
				(thermal_gap 0.5)
				(thermal_bridge_width 0.5)
				(island_removal_mode 0)
			)
			(polygon
				(pts
					(arc
						(start 16.599916 -303.90084)
						(mid 8.598916 -295.89984)
						(end 16.599916 -287.89884)
					)
					(arc
						(start 16.599916 -287.89884)
						(mid 18.035016 -289.33394)
						(end 16.599916 -290.76904)
					)
					(arc
						(start 16.599916 -290.76904)
						(mid 11.469116 -295.89984)
						(end 16.599916 -301.03064)
					)
					(arc
						(start 16.599916 -301.03064)
						(mid 18.035016 -302.46574)
						(end 16.599916 -303.90084)
					)
				)
			)
		)
		(zone
			(layer "F.Cu")
			(hatch none 0.5)
			(connect_pads
				(clearance 0)
			)
			(min_thickness 0.25)
			(keepout
				(tracks not_allowed)
				(vias allowed)
				(pads allowed)
				(copperpour not_allowed)
				(footprints allowed)
			)
			(placement
				(enabled no)
				(sheetname "")
			)
			(fill
				(thermal_gap 0.5)
				(thermal_bridge_width 0.5)
				(island_removal_mode 0)
			)
			(polygon
				(pts
					(arc
						(start 16.599916 -303.90084)
						(mid 24.600916 -295.89984)
						(end 16.599916 -287.89884)
					)
					(arc
						(start 16.599916 -287.89884)
						(mid 15.164816 -289.33394)
						(end 16.599916 -290.76904)
					)
					(arc
						(start 16.599916 -290.76904)
						(mid 21.730716 -295.89984)
						(end 16.599916 -301.03064)
					)
					(arc
						(start 16.599916 -301.03064)
						(mid 15.164816 -302.46574)
						(end 16.599916 -303.90084)
					)
				)
			)
		)
		(zone
			(layers "F.Cu" "B.Cu" "In1.Cu" "In2.Cu" "In3.Cu" "In4.Cu" "In5.Cu" "In6.Cu")
			(hatch none 0.5)
			(connect_pads
				(clearance 0)
			)
			(min_thickness 0.25)
			(keepout
				(tracks not_allowed)
				(vias allowed)
				(pads allowed)
				(copperpour not_allowed)
				(footprints allowed)
			)
			(placement
				(enabled no)
				(sheetname "")
			)
			(fill
				(thermal_gap 0.5)
				(thermal_bridge_width 0.5)
				(island_removal_mode 0)
			)
			(polygon
				(pts
					(arc
						(start 16.599916 -293.38778)
						(mid 16.599916 -298.4119)
						(end 16.599916 -293.38778)
					)
				)
			)
		)
	)
	(footprint ""
		(layer "F.Cu")
		(at 16.599916 -118.09984)
		(property "Reference" "H10"
			(at -7.888224 -6.127242 0)
			(unlocked yes)
			(layer "F.SilkS")
			(effects
				(font
					(size 0.7874 0.5842)
					(thickness 0.1524)
				)
				(justify left)
			)
		)
		(property "Value" ""
			(at 0 0 0)
			(layer "F.Fab")
			(effects
				(font
					(size 1.27 1.27)
				)
			)
		)
		(duplicate_pad_numbers_are_jumpers no)
		(fp_circle
			(center 0 0)
			(end 7.999984 0)
			(stroke
				(width 0.1524)
				(type default)
			)
			(fill no)
			(layer "F.SilkS")
		)
		(fp_circle
			(center 0 0)
			(end 14.7066 0)
			(stroke
				(width 0.1524)
				(type default)
			)
			(fill no)
			(layer "B.SilkS")
		)
		(fp_poly
			(pts
				(arc
					(start 0 5.0038)
					(mid 0 -5.0038)
					(end 0 5.0038)
				)
			)
			(stroke
				(width 0)
				(type default)
			)
			(fill no)
			(layer "F.CrtYd")
		)
		(pad "" np_thru_hole circle
			(at 0 0)
			(size 4.0132 4.0132)
			(drill 4.0132)
			(layers "*.Cu" "*.Mask")
			(clearance 0.381)
			(thermal_gap 0.381)
		)
		(pad "2" thru_hole circle
			(at 0 -3.50012)
			(size 0.762 0.762)
			(drill 0.5588)
			(layers "*.Cu" "*.Mask")
			(remove_unused_layers no)
			(net "GND")
			(clearance 0.1524)
			(thermal_gap 0.1524)
		)
		(pad "3" thru_hole circle
			(at -2.500122 -2.500122)
			(size 0.762 0.762)
			(drill 0.5588)
			(layers "*.Cu" "*.Mask")
			(remove_unused_layers no)
			(net "GND")
			(clearance 0.1524)
			(thermal_gap 0.1524)
		)
		(pad "4" thru_hole circle
			(at -3.50012 0)
			(size 0.762 0.762)
			(drill 0.5588)
			(layers "*.Cu" "*.Mask")
			(remove_unused_layers no)
			(net "GND")
			(clearance 0.1524)
			(thermal_gap 0.1524)
		)
		(pad "5" thru_hole circle
			(at -2.500122 2.500122)
			(size 0.762 0.762)
			(drill 0.5588)
			(layers "*.Cu" "*.Mask")
			(remove_unused_layers no)
			(net "GND")
			(clearance 0.1524)
			(thermal_gap 0.1524)
		)
		(pad "6" thru_hole circle
			(at 0 3.50012)
			(size 0.762 0.762)
			(drill 0.5588)
			(layers "*.Cu" "*.Mask")
			(remove_unused_layers no)
			(net "GND")
			(clearance 0.1524)
			(thermal_gap 0.1524)
		)
		(pad "7" thru_hole circle
			(at 2.500122 2.500122)
			(size 0.762 0.762)
			(drill 0.5588)
			(layers "*.Cu" "*.Mask")
			(remove_unused_layers no)
			(net "GND")
			(clearance 0.1524)
			(thermal_gap 0.1524)
		)
		(pad "8" thru_hole circle
			(at 3.50012 0)
			(size 0.762 0.762)
			(drill 0.5588)
			(layers "*.Cu" "*.Mask")
			(remove_unused_layers no)
			(net "GND")
			(clearance 0.1524)
			(thermal_gap 0.1524)
		)
		(pad "9" thru_hole circle
			(at 2.500122 -2.500122)
			(size 0.762 0.762)
			(drill 0.5588)
			(layers "*.Cu" "*.Mask")
			(remove_unused_layers no)
			(net "GND")
			(clearance 0.1524)
			(thermal_gap 0.1524)
		)
		(zone
			(layer "F.Cu")
			(hatch none 0.5)
			(connect_pads
				(clearance 0)
			)
			(min_thickness 0.25)
			(keepout
				(tracks not_allowed)
				(vias allowed)
				(pads allowed)
				(copperpour not_allowed)
				(footprints allowed)
			)
			(placement
				(enabled no)
				(sheetname "")
			)
			(fill
				(thermal_gap 0.5)
				(thermal_bridge_width 0.5)
				(island_removal_mode 0)
			)
			(polygon
				(pts
					(arc
						(start 16.599916 -126.10084)
						(mid 8.598916 -118.09984)
						(end 16.599916 -110.09884)
					)
					(arc
						(start 16.599916 -110.09884)
						(mid 18.035016 -111.53394)
						(end 16.599916 -112.96904)
					)
					(arc
						(start 16.599916 -112.96904)
						(mid 11.469116 -118.09984)
						(end 16.599916 -123.23064)
					)
					(arc
						(start 16.599916 -123.23064)
						(mid 18.035016 -124.66574)
						(end 16.599916 -126.10084)
					)
				)
			)
		)
		(zone
			(layer "F.Cu")
			(hatch none 0.5)
			(connect_pads
				(clearance 0)
			)
			(min_thickness 0.25)
			(keepout
				(tracks not_allowed)
				(vias allowed)
				(pads allowed)
				(copperpour not_allowed)
				(footprints allowed)
			)
			(placement
				(enabled no)
				(sheetname "")
			)
			(fill
				(thermal_gap 0.5)
				(thermal_bridge_width 0.5)
				(island_removal_mode 0)
			)
			(polygon
				(pts
					(arc
						(start 16.599916 -126.10084)
						(mid 24.600916 -118.09984)
						(end 16.599916 -110.09884)
					)
					(arc
						(start 16.599916 -110.09884)
						(mid 15.164816 -111.53394)
						(end 16.599916 -112.96904)
					)
					(arc
						(start 16.599916 -112.96904)
						(mid 21.730716 -118.09984)
						(end 16.599916 -123.23064)
					)
					(arc
						(start 16.599916 -123.23064)
						(mid 15.164816 -124.66574)
						(end 16.599916 -126.10084)
					)
				)
			)
		)
		(zone
			(layers "F.Cu" "B.Cu" "In1.Cu" "In2.Cu" "In3.Cu" "In4.Cu" "In5.Cu" "In6.Cu")
			(hatch none 0.5)
			(connect_pads
				(clearance 0)
			)
			(min_thickness 0.25)
			(keepout
				(tracks not_allowed)
				(vias allowed)
				(pads allowed)
				(copperpour not_allowed)
				(footprints allowed)
			)
			(placement
				(enabled no)
				(sheetname "")
			)
			(fill
				(thermal_gap 0.5)
				(thermal_bridge_width 0.5)
				(island_removal_mode 0)
			)
			(polygon
				(pts
					(arc
						(start 16.599916 -115.58778)
						(mid 16.599916 -120.6119)
						(end 16.599916 -115.58778)
					)
				)
			)
		)
	)
)
